# T6G (Grand Teton) — schematic netlist excerpt (pin names and nets, part order shuffled) for the footprints in the layout excerpt that follows; sources: Cadence DE-HDL packaged netlist, KiCad conversion of 04192023_DAF0TMB3IC0_F0TG_MB_C_brd_V02_OCP.brd

R6271  Q_RES  0 5% CHIP  pkg 0402LF  page 178 : A = USB_HUB2_TI_USB_DP_DN1_MRP_CFG_STRAP ; B = USB_HUB2_MRP_CFG_STRAP
C1539  Q_CAP_DIFFBUS  DIFF BUS_0.22UF 6.3V 20% X6S  pkg C0201  page 67 : \1\ = P5E_CPU1_P3_TX_C_DP<4> ; \2\ = P5E_CPU1_P3_TX_DP<4>
R8072  Q_RES  0 5% CHIP  pkg 0402LF  page 200 : A = SMB_SCM_2_R5_SDA ; B = SMB_DIO_PVDDCR_CPU1_P0_R

(kicad_pcb
	(version 20260206)
	(generator "pcbnew")
	(generator_version "10.0")
	(general
		(thickness 1.6)
		(legacy_teardrops no)
	)
	(paper "A4")
	(title_block
		(title "04192023_DAF0TMB3IC0_F0TG_MB_C_brd_V02_OCP.brd")
		(comment 1 "Grand Teton / footprints 2101-2103 of 8354")
	)
	(layers
		(0 "F.Cu" signal "TOP")
		(4 "In1.Cu" signal "GND")
		(6 "In2.Cu" signal "IN1")
		(8 "In3.Cu" signal "GND1")
		(10 "In4.Cu" signal "IN2")
		(12 "In5.Cu" signal "GND2")
		(14 "In6.Cu" signal "IN3")
		(16 "In7.Cu" signal "GND3")
		(18 "In8.Cu" signal "VCC")
		(20 "In9.Cu" signal "VCC1")
		(22 "In10.Cu" signal "GND4")
		(24 "In11.Cu" signal "IN4")
		(26 "In12.Cu" signal "GND5")
		(28 "In13.Cu" signal "IN5")
		(30 "In14.Cu" signal "GND6")
		(32 "In15.Cu" signal "IN6")
		(34 "In16.Cu" signal "GND7")
		(2 "B.Cu" signal "BOTTOM")
		(9 "F.Adhes" user "F.Adhesive")
		(11 "B.Adhes" user "B.Adhesive")
		(13 "F.Paste" user "Package Geometry/Pastemask Top")
		(15 "B.Paste" user "Package Geometry/Pastemask Bottom")
		(5 "F.SilkS" user "Ref Des/Silkscreen Top")
		(7 "B.SilkS" user "Ref Des/Silkscreen Bottom")
		(1 "F.Mask" user "Board Geometry/Soldermask Top")
		(3 "B.Mask" user "Board Geometry/Soldermask Bottom")
		(17 "Dwgs.User" user "User.Drawings")
		(19 "Cmts.User" user "User.Comments")
		(21 "Eco1.User" user "User.Eco1")
		(23 "Eco2.User" user "User.Eco2")
		(25 "Edge.Cuts" user "Board Geometry/Outline")
		(27 "Margin" user)
		(31 "F.CrtYd" user "Package Geometry/Place Bound Top")
		(29 "B.CrtYd" user "Package Geometry/Place Bound Bottom")
		(35 "F.Fab" user "Ref Des/Assembly Top")
		(33 "B.Fab" user "Ref Des/Assembly Bottom")
	)
	(footprint ""
		(layer "F.Cu")
		(at 304.419 -367.665)
		(property "Reference" "R8072"
			(at 0 0 0)
			(layer "F.SilkS")
			(hide yes)
			(effects
				(font
					(size 1.27 1.27)
				)
			)
		)
		(property "Value" ""
			(at 0 0 0)
			(layer "F.Fab")
			(effects
				(font
					(size 1.27 1.27)
				)
			)
		)
		(duplicate_pad_numbers_are_jumpers no)
		(fp_line
			(start -0.7874 -0.4064)
			(end 0.7874 -0.4064)
			(stroke
				(width 0.1524)
				(type default)
			)
			(layer "F.SilkS")
		)
		(fp_line
			(start -0.7874 0.4064)
			(end -0.7874 -0.4064)
			(stroke
				(width 0.1524)
				(type default)
			)
			(layer "F.SilkS")
		)
		(fp_line
			(start 0.7874 -0.4064)
			(end 0.7874 0.4064)
			(stroke
				(width 0.1524)
				(type default)
			)
			(layer "F.SilkS")
		)
		(fp_line
			(start 0.7874 0.4064)
			(end -0.7874 0.4064)
			(stroke
				(width 0.1524)
				(type default)
			)
			(layer "F.SilkS")
		)
		(fp_line
			(start -0.67945 -0.305054)
			(end -0.12065 -0.305054)
			(stroke
				(width 0.1)
				(type default)
			)
			(layer "F.Fab")
		)
		(fp_line
			(start -0.67945 0.3048)
			(end -0.67945 -0.305054)
			(stroke
				(width 0.1)
				(type default)
			)
			(layer "F.Fab")
		)
		(fp_line
			(start -0.12065 -0.305054)
			(end -0.12065 -0.2794)
			(stroke
				(width 0.1)
				(type default)
			)
			(layer "F.Fab")
		)
		(fp_line
			(start -0.12065 -0.2794)
			(end 0.12065 -0.2794)
			(stroke
				(width 0.1)
				(type default)
			)
			(layer "F.Fab")
		)
		(fp_line
			(start -0.12065 0.2794)
			(end -0.12065 0.3048)
			(stroke
				(width 0.1)
				(type default)
			)
			(layer "F.Fab")
		)
		(fp_line
			(start -0.12065 0.3048)
			(end -0.67945 0.3048)
			(stroke
				(width 0.1)
				(type default)
			)
			(layer "F.Fab")
		)
		(fp_line
			(start 0.120396 0.2794)
			(end -0.12065 0.2794)
			(stroke
				(width 0.1)
				(type default)
			)
			(layer "F.Fab")
		)
		(fp_line
			(start 0.120396 0.3048)
			(end 0.120396 0.2794)
			(stroke
				(width 0.1)
				(type default)
			)
			(layer "F.Fab")
		)
		(fp_line
			(start 0.12065 -0.3048)
			(end 0.67945 -0.3048)
			(stroke
				(width 0.1)
				(type default)
			)
			(layer "F.Fab")
		)
		(fp_line
			(start 0.12065 -0.2794)
			(end 0.12065 -0.3048)
			(stroke
				(width 0.1)
				(type default)
			)
			(layer "F.Fab")
		)
		(fp_line
			(start 0.67945 -0.3048)
			(end 0.67945 0.3048)
			(stroke
				(width 0.1)
				(type default)
			)
			(layer "F.Fab")
		)
		(fp_line
			(start 0.67945 0.3048)
			(end 0.120396 0.3048)
			(stroke
				(width 0.1)
				(type default)
			)
			(layer "F.Fab")
		)
		(pad "1" smd circle
			(at -0.40005 0)
			(size 0 0)
			(layers "F.Cu" "F.Mask" "F.Paste")
			(net "SMB_SCM_2_R5_SDA")
		)
		(pad "2" smd circle
			(at 0.40005 0)
			(size 0 0)
			(layers "F.Cu" "F.Mask" "F.Paste")
			(net "SMB_DIO_PVDDCR_CPU1_P0_R")
		)
	)
	(footprint ""
		(layer "F.Cu")
		(at 110.152942 -21.7678 -90)
		(property "Reference" "R6271"
			(at 0 0 270)
			(layer "F.SilkS")
			(hide yes)
			(effects
				(font
					(size 1.27 1.27)
				)
			)
		)
		(property "Value" ""
			(at 0 0 270)
			(layer "F.Fab")
			(effects
				(font
					(size 1.27 1.27)
				)
			)
		)
		(duplicate_pad_numbers_are_jumpers no)
		(fp_line
			(start -0.7874 0.4064)
			(end -0.7874 -0.4064)
			(stroke
				(width 0.1524)
				(type default)
			)
			(layer "F.SilkS")
		)
		(fp_line
			(start 0.7874 0.4064)
			(end -0.7874 0.4064)
			(stroke
				(width 0.1524)
				(type default)
			)
			(layer "F.SilkS")
		)
		(fp_line
			(start -0.7874 -0.4064)
			(end 0.7874 -0.4064)
			(stroke
				(width 0.1524)
				(type default)
			)
			(layer "F.SilkS")
		)
		(fp_line
			(start 0.7874 -0.4064)
			(end 0.7874 0.4064)
			(stroke
				(width 0.1524)
				(type default)
			)
			(layer "F.SilkS")
		)
		(fp_line
			(start -0.67945 0.3048)
			(end -0.67945 -0.305054)
			(stroke
				(width 0.1)
				(type default)
			)
			(layer "F.Fab")
		)
		(fp_line
			(start -0.12065 0.3048)
			(end -0.67945 0.3048)
			(stroke
				(width 0.1)
				(type default)
			)
			(layer "F.Fab")
		)
		(fp_line
			(start 0.120396 0.3048)
			(end 0.120396 0.2794)
			(stroke
				(width 0.1)
				(type default)
			)
			(layer "F.Fab")
		)
		(fp_line
			(start 0.67945 0.3048)
			(end 0.120396 0.3048)
			(stroke
				(width 0.1)
				(type default)
			)
			(layer "F.Fab")
		)
		(fp_line
			(start -0.12065 0.2794)
			(end -0.12065 0.3048)
			(stroke
				(width 0.1)
				(type default)
			)
			(layer "F.Fab")
		)
		(fp_line
			(start 0.120396 0.2794)
			(end -0.12065 0.2794)
			(stroke
				(width 0.1)
				(type default)
			)
			(layer "F.Fab")
		)
		(fp_line
			(start -0.12065 -0.2794)
			(end 0.12065 -0.2794)
			(stroke
				(width 0.1)
				(type default)
			)
			(layer "F.Fab")
		)
		(fp_line
			(start 0.12065 -0.2794)
			(end 0.12065 -0.3048)
			(stroke
				(width 0.1)
				(type default)
			)
			(layer "F.Fab")
		)
		(fp_line
			(start 0.12065 -0.3048)
			(end 0.67945 -0.3048)
			(stroke
				(width 0.1)
				(type default)
			)
			(layer "F.Fab")
		)
		(fp_line
			(start 0.67945 -0.3048)
			(end 0.67945 0.3048)
			(stroke
				(width 0.1)
				(type default)
			)
			(layer "F.Fab")
		)
		(fp_line
			(start -0.67945 -0.305054)
			(end -0.12065 -0.305054)
			(stroke
				(width 0.1)
				(type default)
			)
			(layer "F.Fab")
		)
		(fp_line
			(start -0.12065 -0.305054)
			(end -0.12065 -0.2794)
			(stroke
				(width 0.1)
				(type default)
			)
			(layer "F.Fab")
		)
		(pad "1" smd circle
			(at -0.40005 0 270)
			(size 0 0)
			(layers "F.Cu" "F.Mask" "F.Paste")
			(net "USB_HUB2_TI_USB_DP_DN1_MRP_CFG_STRAP")
		)
		(pad "2" smd circle
			(at 0.40005 0 270)
			(size 0 0)
			(layers "F.Cu" "F.Mask" "F.Paste")
			(net "USB_HUB2_MRP_CFG_STRAP")
		)
	)
	(footprint ""
		(layer "F.Cu")
		(at 115.195096 -375.49963 -90)
		(property "Reference" "C1539"
			(at 0 0 270)
			(layer "F.SilkS")
			(hide yes)
			(effects
				(font
					(size 1.27 1.27)
				)
			)
		)
		(property "Value" ""
			(at 0 0 270)
			(layer "F.Fab")
			(effects
				(font
					(size 1.27 1.27)
				)
			)
		)
		(duplicate_pad_numbers_are_jumpers no)
		(fp_line
			(start -0.299974 0.150114)
			(end -0.299974 -0.150114)
			(stroke
				(width 0.1)
				(type default)
			)
			(layer "F.Fab")
		)
		(fp_line
			(start 0.299974 0.150114)
			(end -0.299974 0.150114)
			(stroke
				(width 0.1)
				(type default)
			)
			(layer "F.Fab")
		)
		(fp_line
			(start -0.299974 -0.150114)
			(end 0.299974 -0.150114)
			(stroke
				(width 0.1)
				(type default)
			)
			(layer "F.Fab")
		)
		(fp_line
			(start 0.299974 -0.150114)
			(end 0.299974 0.150114)
			(stroke
				(width 0.1)
				(type default)
			)
			(layer "F.Fab")
		)
		(pad "1" smd rect
			(at -0.2667 0 270)
			(size 0.3048 0.381)
			(layers "F.Cu" "F.Mask" "F.Paste")
			(net "P5E_CPU1_P3_TX_C_DP<4>")
		)
		(pad "2" smd rect
			(at 0.2667 0 270)
			(size 0.3048 0.381)
			(layers "F.Cu" "F.Mask" "F.Paste")
			(net "P5E_CPU1_P3_TX_DP<4>")
		)
	)
)
